(kicad_pcb
	(version 20260206)
	(generator "pcbnew")
	(generator_version "10.0")
	(general
		(thickness 1.6)
		(legacy_teardrops no)
	)
	(paper "A4")
	(title_block
		(title "Bryce Canyon_R.DPB_16317-1_OCP.brd")
		(comment 1 "Bryce Canyon / footprints 1700-1706 of 2099")
	)
	(layers
		(0 "F.Cu" signal "TOP")
		(4 "In1.Cu" signal "L2GND")
		(6 "In2.Cu" signal "L3")
		(8 "In3.Cu" signal "L4VCC")
		(10 "In4.Cu" signal "L5VCC")
		(12 "In5.Cu" signal "L6")
		(14 "In6.Cu" signal "L7GND")
		(2 "B.Cu" signal "BOTTOM")
		(9 "F.Adhes" user "F.Adhesive")
		(11 "B.Adhes" user "B.Adhesive")
		(13 "F.Paste" user "Package Geometry/Pastemask Top")
		(15 "B.Paste" user "Package Geometry/Pastemask Bottom")
		(5 "F.SilkS" user "Ref Des/Silkscreen Top")
		(7 "B.SilkS" user "Ref Des/Silkscreen Bottom")
		(1 "F.Mask" user "Board Geometry/Soldermask Top")
		(3 "B.Mask" user "Board Geometry/Soldermask Bottom")
		(17 "Dwgs.User" user "User.Drawings")
		(19 "Cmts.User" user "User.Comments")
		(21 "Eco1.User" user "User.Eco1")
		(23 "Eco2.User" user "User.Eco2")
		(25 "Edge.Cuts" user "Board Geometry/Outline")
		(27 "Margin" user)
		(31 "F.CrtYd" user "Package Geometry/Place Bound Top")
		(29 "B.CrtYd" user "Package Geometry/Place Bound Bottom")
		(35 "F.Fab" user "Ref Des/Assembly Top")
		(33 "B.Fab" user "Ref Des/Assembly Bottom")
	)
	(footprint ""
		(layer "F.Cu")
		(at 208.90738 -247.88622 180)
		(property "Reference" "R38"
			(at 0 0 180)
			(layer "F.SilkS")
			(hide yes)
			(effects
				(font
					(size 1.27 1.27)
				)
			)
		)
		(property "Value" "4K7R2F-GP"
			(at 0.064008 -3.993896 180)
			(unlocked yes)
			(layer "F.Fab")
			(hide yes)
			(effects
				(font
					(size 1.016 1.016)
					(thickness 0.1524)
				)
			)
		)
		(property "Device Type" "R402H16"
			(at 0.064008 -5.517896 180)
			(unlocked yes)
			(layer "F.Fab")
			(hide yes)
			(effects
				(font
					(size 1.016 1.016)
					(thickness 0.1524)
				)
			)
		)
		(duplicate_pad_numbers_are_jumpers no)
		(fp_line
			(start 0.508 -0.9398)
			(end -0.508 -0.9398)
			(stroke
				(width 0.1524)
				(type default)
			)
			(layer "F.SilkS")
		)
		(fp_line
			(start -0.508 -0.9398)
			(end -0.508 0.9398)
			(stroke
				(width 0.1524)
				(type default)
			)
			(layer "F.SilkS")
		)
		(fp_rect
			(start -0.508 0.9398)
			(end 0.508 -0.9398)
			(stroke
				(width 0)
				(type default)
			)
			(fill no)
			(layer "F.CrtYd")
		)
		(fp_rect
			(start -0.508 0.9398)
			(end 0.508 -0.9398)
			(stroke
				(width 0)
				(type default)
			)
			(fill no)
			(layer "F.Fab")
		)
		(pad "1" smd custom
			(at 0 -0.4445 180)
			(size 0.1397 0.1397)
			(layers "F.Cu" "F.Mask" "F.Paste")
			(net "IO_EXP4_A2")
			(options
				(clearance outline)
				(anchor circle)
			)
			(primitives
				(gr_poly
					(pts
						(arc
							(start -0.1778 -0.2794)
							(mid -0.249642 -0.249642)
							(end -0.2794 -0.1778)
						)
						(arc
							(start -0.2794 0.1778)
							(mid -0.249642 0.249642)
							(end -0.1778 0.2794)
						)
						(arc
							(start 0.1778 0.2794)
							(mid 0.249642 0.249642)
							(end 0.2794 0.1778)
						)
						(arc
							(start 0.2794 -0.1778)
							(mid 0.249642 -0.249642)
							(end 0.1778 -0.2794)
						)
					)
					(width 0)
					(fill yes)
				)
			)
		)
		(pad "2" smd custom
			(at 0 0.4445 180)
			(size 0.1397 0.1397)
			(layers "F.Cu" "F.Mask" "F.Paste")
			(net "GND")
			(options
				(clearance outline)
				(anchor circle)
			)
			(primitives
				(gr_poly
					(pts
						(arc
							(start -0.1778 -0.2794)
							(mid -0.249642 -0.249642)
							(end -0.2794 -0.1778)
						)
						(arc
							(start -0.2794 0.1778)
							(mid -0.249642 0.249642)
							(end -0.1778 0.2794)
						)
						(arc
							(start 0.1778 0.2794)
							(mid 0.249642 0.249642)
							(end 0.2794 0.1778)
						)
						(arc
							(start 0.2794 -0.1778)
							(mid 0.249642 -0.249642)
							(end 0.1778 -0.2794)
						)
					)
					(width 0)
					(fill yes)
				)
			)
		)
	)
	(footprint ""
		(layer "F.Cu")
		(at 449.78955 -248.750074 -90)
		(property "Reference" "VIA22"
			(at 0 0 270)
			(layer "F.SilkS")
			(hide yes)
			(effects
				(font
					(size 1.27 1.27)
				)
			)
		)
		(property "Value" "100OHM-8L-2D36MM-L16-GP"
			(at -3.4036 -0.4572 270)
			(unlocked yes)
			(layer "F.Fab")
			(hide yes)
			(effects
				(font
					(size 1.016 1.016)
					(thickness 0.1524)
				)
			)
		)
		(property "Device Type" "VIA-PCIE-4P-427097"
			(at -3.4036 -1.9812 270)
			(unlocked yes)
			(layer "F.Fab")
			(hide yes)
			(effects
				(font
					(size 1.016 1.016)
					(thickness 0.1524)
				)
			)
		)
		(duplicate_pad_numbers_are_jumpers no)
		(fp_rect
			(start -2.1336 0.4826)
			(end 2.1336 -0.4826)
			(stroke
				(width 0)
				(type default)
			)
			(fill no)
			(layer "F.CrtYd")
		)
		(fp_rect
			(start -2.1336 0.4826)
			(end 2.1336 -0.4826)
			(stroke
				(width 0)
				(type default)
			)
			(fill no)
			(layer "F.Fab")
		)
		(pad "1" thru_hole circle
			(at -1.651 0 270)
			(size 0.508 0.508)
			(drill 0.254)
			(layers "*.Cu" "*.Mask")
			(remove_unused_layers no)
			(net "GND")
			(clearance 0.2286)
			(thermal_gap 0.2286)
		)
		(pad "2" thru_hole circle
			(at -0.635 0 270)
			(size 0.508 0.508)
			(drill 0.254)
			(layers "*.Cu" "*.Mask")
			(remove_unused_layers no)
			(net "PHY_DRV_B_TO_SCC_B_10_DP")
			(clearance 0.2286)
			(thermal_gap 0.2286)
		)
		(pad "3" thru_hole circle
			(at 0.635 0 270)
			(size 0.508 0.508)
			(drill 0.254)
			(layers "*.Cu" "*.Mask")
			(remove_unused_layers no)
			(net "PHY_DRV_B_TO_SCC_B_10_DN")
			(clearance 0.2286)
			(thermal_gap 0.2286)
		)
		(pad "4" thru_hole circle
			(at 1.651 0 270)
			(size 0.508 0.508)
			(drill 0.254)
			(layers "*.Cu" "*.Mask")
			(remove_unused_layers no)
			(net "GND")
			(clearance 0.2286)
			(thermal_gap 0.2286)
		)
	)
	(footprint ""
		(layer "F.Cu")
		(at 441.349892 -65.39992)
		(property "Reference" "LED23"
			(at 0 0 0)
			(layer "F.SilkS")
			(hide yes)
			(effects
				(font
					(size 1.27 1.27)
				)
			)
		)
		(property "Value" "LED-BY-19-GP"
			(at -2.132076 1.414018 0)
			(unlocked yes)
			(layer "F.Fab")
			(hide yes)
			(effects
				(font
					(size 1.016 1.016)
					(thickness 0.1524)
				)
			)
		)
		(property "Device Type" "LED-1615-4PH26"
			(at -2.132076 -0.109982 0)
			(unlocked yes)
			(layer "F.Fab")
			(hide yes)
			(effects
				(font
					(size 1.016 1.016)
					(thickness 0.1524)
				)
			)
		)
		(duplicate_pad_numbers_are_jumpers no)
		(fp_line
			(start -1.2954 0.254)
			(end -1.2954 1.6002)
			(stroke
				(width 0.508)
				(type default)
			)
			(layer "F.SilkS")
		)
		(fp_line
			(start -1.2954 1.6002)
			(end 1.2954 1.6002)
			(stroke
				(width 0.508)
				(type default)
			)
			(layer "F.SilkS")
		)
		(fp_line
			(start -1.1176 -1.4224)
			(end 1.1176 -1.4224)
			(stroke
				(width 0.1524)
				(type default)
			)
			(layer "F.SilkS")
		)
		(fp_line
			(start -1.1176 1.4224)
			(end -1.1176 -1.4224)
			(stroke
				(width 0.1524)
				(type default)
			)
			(layer "F.SilkS")
		)
		(fp_line
			(start 1.1176 -1.4224)
			(end 1.1176 1.4224)
			(stroke
				(width 0.1524)
				(type default)
			)
			(layer "F.SilkS")
		)
		(fp_line
			(start 1.1176 1.4224)
			(end -1.1176 1.4224)
			(stroke
				(width 0.1524)
				(type default)
			)
			(layer "F.SilkS")
		)
		(fp_line
			(start 1.2954 1.6002)
			(end 1.2954 0.254)
			(stroke
				(width 0.508)
				(type default)
			)
			(layer "F.SilkS")
		)
		(fp_rect
			(start -0.7493 0.8001)
			(end 0.7493 -0.8001)
			(stroke
				(width 0)
				(type default)
			)
			(fill no)
			(layer "F.CrtYd")
		)
		(fp_poly
			(pts
				(xy -1.3716 1.6764) (xy -1.3716 -1.6764) (xy 1.3716 -1.6764) (xy 1.3716 0.0635) (xy 0.7493 0.0635)
				(xy 0.7493 -0.8001) (xy -0.7493 -0.8001) (xy -0.7493 0.8001) (xy 0.7493 0.8001) (xy 0.7493 0.0762)
				(xy 1.3716 0.0762) (xy 1.3716 1.6764)
			)
			(stroke
				(width 0)
				(type default)
			)
			(fill no)
			(layer "F.CrtYd")
		)
		(fp_rect
			(start -1.3716 1.6764)
			(end 1.3716 -1.6764)
			(stroke
				(width 0)
				(type default)
			)
			(fill no)
			(layer "F.Fab")
		)
		(pad "1" smd rect
			(at 0.50038 -0.73025)
			(size 0.7112 0.8636)
			(layers "F.Cu" "F.Mask" "F.Paste")
			(net "DRV_ACT_22")
		)
		(pad "2" smd rect
			(at -0.50038 -0.73025)
			(size 0.7112 0.8636)
			(layers "F.Cu" "F.Mask" "F.Paste")
			(net "FLT_HDD22")
		)
		(pad "3" smd rect
			(at 0.50038 0.73025)
			(size 0.7112 0.8636)
			(layers "F.Cu" "F.Mask" "F.Paste")
			(net "DRV_ACT_22_N")
		)
		(pad "4" smd rect
			(at -0.50038 0.73025)
			(size 0.7112 0.8636)
			(layers "F.Cu" "F.Mask" "F.Paste")
			(net "FLT_HDD22_N")
		)
	)
	(footprint ""
		(layer "F.Cu")
		(at 447.834512 -244.660674 -90)
		(property "Reference" "C159"
			(at 0 0 270)
			(layer "F.SilkS")
			(hide yes)
			(effects
				(font
					(size 1.27 1.27)
				)
			)
		)
		(property "Value" "SCD01U16V1KX-GP"
			(at -2.8321 -1.7399 270)
			(unlocked yes)
			(layer "F.Fab")
			(hide yes)
			(effects
				(font
					(size 1.016 1.016)
					(thickness 0.1524)
				)
			)
		)
		(property "Device Type" "C0201H13"
			(at -2.8321 -3.2639 270)
			(unlocked yes)
			(layer "F.Fab")
			(hide yes)
			(effects
				(font
					(size 1.016 1.016)
					(thickness 0.1524)
				)
			)
		)
		(duplicate_pad_numbers_are_jumpers no)
		(fp_rect
			(start -0.2794 0.6477)
			(end 0.2794 -0.6477)
			(stroke
				(width 0)
				(type default)
			)
			(fill no)
			(layer "F.CrtYd")
		)
		(fp_rect
			(start -0.2794 0.6477)
			(end 0.2794 -0.6477)
			(stroke
				(width 0)
				(type default)
			)
			(fill no)
			(layer "F.Fab")
		)
		(pad "1" smd custom
			(at 0 -0.2794 270)
			(size 0.0762 0.0762)
			(layers "F.Cu" "F.Mask" "F.Paste")
			(net "SAS_HDD_RX_P10")
			(options
				(clearance outline)
				(anchor circle)
			)
			(primitives
				(gr_poly
					(pts
						(arc
							(start 0.1524 -0.127)
							(mid 0.137521 -0.162921)
							(end 0.1016 -0.1778)
						)
						(arc
							(start -0.1016 -0.1778)
							(mid -0.137521 -0.162921)
							(end -0.1524 -0.127)
						)
						(arc
							(start -0.1524 0.127)
							(mid -0.137521 0.162921)
							(end -0.1016 0.1778)
						)
						(arc
							(start 0.1016 0.1778)
							(mid 0.137521 0.162921)
							(end 0.1524 0.127)
						)
					)
					(width 0)
					(fill yes)
				)
			)
		)
		(pad "2" smd custom
			(at 0 0.2794 270)
			(size 0.0762 0.0762)
			(layers "F.Cu" "F.Mask" "F.Paste")
			(net "PHY_SCC_B_TO_DRV_B_10_DP")
			(options
				(clearance outline)
				(anchor circle)
			)
			(primitives
				(gr_poly
					(pts
						(arc
							(start 0.1524 -0.127)
							(mid 0.137521 -0.162921)
							(end 0.1016 -0.1778)
						)
						(arc
							(start -0.1016 -0.1778)
							(mid -0.137521 -0.162921)
							(end -0.1524 -0.127)
						)
						(arc
							(start -0.1524 0.127)
							(mid -0.137521 0.162921)
							(end -0.1016 0.1778)
						)
						(arc
							(start 0.1016 0.1778)
							(mid 0.137521 0.162921)
							(end 0.1524 0.127)
						)
					)
					(width 0)
					(fill yes)
				)
			)
		)
	)
	(footprint ""
		(layer "F.Cu")
		(at 67.31 -32.8168 180)
		(property "Reference" "R649"
			(at 0 0 180)
			(layer "F.SilkS")
			(hide yes)
			(effects
				(font
					(size 1.27 1.27)
				)
			)
		)
		(property "Value" "220R3F-1-GP"
			(at -0.0254 -2.5146 180)
			(unlocked yes)
			(layer "F.Fab")
			(hide yes)
			(effects
				(font
					(size 1.016 1.016)
					(thickness 0.1524)
				)
			)
		)
		(property "Device Type" "R603H22"
			(at -0.0254 -4.0386 180)
			(unlocked yes)
			(layer "F.Fab")
			(hide yes)
			(effects
				(font
					(size 1.016 1.016)
					(thickness 0.1524)
				)
			)
		)
		(duplicate_pad_numbers_are_jumpers no)
		(fp_line
			(start 0.2032 0)
			(end 0.4826 0)
			(stroke
				(width 0.2032)
				(type default)
			)
			(layer "F.SilkS")
		)
		(fp_line
			(start -0.4826 0)
			(end -0.2032 0)
			(stroke
				(width 0.2032)
				(type default)
			)
			(layer "F.SilkS")
		)
		(fp_rect
			(start -0.5842 1.3335)
			(end 0.5842 -1.3335)
			(stroke
				(width 0)
				(type default)
			)
			(fill no)
			(layer "F.CrtYd")
		)
		(fp_rect
			(start -0.5842 1.3335)
			(end 0.5842 -1.3335)
			(stroke
				(width 0)
				(type default)
			)
			(fill no)
			(layer "F.Fab")
		)
		(pad "1" smd custom
			(at 0 -0.762 180)
			(size 0.2159 0.2159)
			(layers "F.Cu" "F.Mask" "F.Paste")
			(net "HDD_PRSNT_25")
			(options
				(clearance outline)
				(anchor circle)
			)
			(primitives
				(gr_poly
					(pts
						(arc
							(start -0.3302 -0.4318)
							(mid -0.402042 -0.402042)
							(end -0.4318 -0.3302)
						)
						(arc
							(start -0.4318 0.3302)
							(mid -0.402042 0.402042)
							(end -0.3302 0.4318)
						)
						(arc
							(start 0.3302 0.4318)
							(mid 0.402042 0.402042)
							(end 0.4318 0.3302)
						)
						(arc
							(start 0.4318 -0.3302)
							(mid 0.402042 -0.402042)
							(end 0.3302 -0.4318)
						)
					)
					(width 0)
					(fill yes)
				)
			)
		)
		(pad "2" smd custom
			(at 0 0.762 180)
			(size 0.2159 0.2159)
			(layers "F.Cu" "F.Mask" "F.Paste")
			(net "DRIVE_B_25_INS")
			(options
				(clearance outline)
				(anchor circle)
			)
			(primitives
				(gr_poly
					(pts
						(arc
							(start -0.3302 -0.4318)
							(mid -0.402042 -0.402042)
							(end -0.4318 -0.3302)
						)
						(arc
							(start -0.4318 0.3302)
							(mid -0.402042 0.402042)
							(end -0.3302 0.4318)
						)
						(arc
							(start 0.3302 0.4318)
							(mid 0.402042 0.402042)
							(end 0.4318 0.3302)
						)
						(arc
							(start 0.4318 -0.3302)
							(mid 0.402042 -0.402042)
							(end 0.3302 -0.4318)
						)
					)
					(width 0)
					(fill yes)
				)
			)
		)
	)
	(footprint ""
		(layer "F.Cu")
		(at 234.2134 -192.786 180)
		(property "Reference" "R512"
			(at 0 0 180)
			(layer "F.SilkS")
			(hide yes)
			(effects
				(font
					(size 1.27 1.27)
				)
			)
		)
		(property "Value" "100KR2F-L1-GP"
			(at 0.064008 -3.993896 180)
			(unlocked yes)
			(layer "F.Fab")
			(hide yes)
			(effects
				(font
					(size 1.016 1.016)
					(thickness 0.1524)
				)
			)
		)
		(property "Device Type" "R402H16"
			(at 0.064008 -5.517896 180)
			(unlocked yes)
			(layer "F.Fab")
			(hide yes)
			(effects
				(font
					(size 1.016 1.016)
					(thickness 0.1524)
				)
			)
		)
		(duplicate_pad_numbers_are_jumpers no)
		(fp_line
			(start 0.508 -0.9398)
			(end -0.508 -0.9398)
			(stroke
				(width 0.1524)
				(type default)
			)
			(layer "F.SilkS")
		)
		(fp_line
			(start -0.508 -0.9398)
			(end -0.508 0.9398)
			(stroke
				(width 0.1524)
				(type default)
			)
			(layer "F.SilkS")
		)
		(fp_rect
			(start -0.508 0.9398)
			(end 0.508 -0.9398)
			(stroke
				(width 0)
				(type default)
			)
			(fill no)
			(layer "F.CrtYd")
		)
		(fp_rect
			(start -0.508 0.9398)
			(end 0.508 -0.9398)
			(stroke
				(width 0)
				(type default)
			)
			(fill no)
			(layer "F.Fab")
		)
		(pad "1" smd custom
			(at 0 -0.4445 180)
			(size 0.1397 0.1397)
			(layers "F.Cu" "F.Mask" "F.Paste")
			(net "GPIO_VCC_U9")
			(options
				(clearance outline)
				(anchor circle)
			)
			(primitives
				(gr_poly
					(pts
						(arc
							(start -0.1778 -0.2794)
							(mid -0.249642 -0.249642)
							(end -0.2794 -0.1778)
						)
						(arc
							(start -0.2794 0.1778)
							(mid -0.249642 0.249642)
							(end -0.1778 0.2794)
						)
						(arc
							(start 0.1778 0.2794)
							(mid 0.249642 0.249642)
							(end 0.2794 0.1778)
						)
						(arc
							(start 0.2794 -0.1778)
							(mid 0.249642 -0.249642)
							(end 0.1778 -0.2794)
						)
					)
					(width 0)
					(fill yes)
				)
			)
		)
		(pad "2" smd custom
			(at 0 0.4445 180)
			(size 0.1397 0.1397)
			(layers "F.Cu" "F.Mask" "F.Paste")
			(net "GND")
			(options
				(clearance outline)
				(anchor circle)
			)
			(primitives
				(gr_poly
					(pts
						(arc
							(start -0.1778 -0.2794)
							(mid -0.249642 -0.249642)
							(end -0.2794 -0.1778)
						)
						(arc
							(start -0.2794 0.1778)
							(mid -0.249642 0.249642)
							(end -0.1778 0.2794)
						)
						(arc
							(start 0.1778 0.2794)
							(mid 0.249642 0.249642)
							(end 0.2794 0.1778)
						)
						(arc
							(start 0.2794 -0.1778)
							(mid 0.249642 -0.249642)
							(end 0.1778 -0.2794)
						)
					)
					(width 0)
					(fill yes)
				)
			)
		)
	)
	(footprint ""
		(layer "F.Cu")
		(at 304.138076 -327.858882)
		(property "Reference" "R97"
			(at 0 0 0)
			(layer "F.SilkS")
			(hide yes)
			(effects
				(font
					(size 1.27 1.27)
				)
			)
		)
		(property "Value" "100KR2F-L1-GP"
			(at 0.064008 -3.993896 0)
			(unlocked yes)
			(layer "F.Fab")
			(hide yes)
			(effects
				(font
					(size 1.016 1.016)
					(thickness 0.1524)
				)
			)
		)
		(property "Device Type" "R402H16"
			(at 0.064008 -5.517896 0)
			(unlocked yes)
			(layer "F.Fab")
			(hide yes)
			(effects
				(font
					(size 1.016 1.016)
					(thickness 0.1524)
				)
			)
		)
		(duplicate_pad_numbers_are_jumpers no)
		(fp_line
			(start -0.508 -0.9398)
			(end -0.508 0.9398)
			(stroke
				(width 0.1524)
				(type default)
			)
			(layer "F.SilkS")
		)
		(fp_line
			(start 0.508 -0.9398)
			(end -0.508 -0.9398)
			(stroke
				(width 0.1524)
				(type default)
			)
			(layer "F.SilkS")
		)
		(fp_rect
			(start -0.508 0.9398)
			(end 0.508 -0.9398)
			(stroke
				(width 0)
				(type default)
			)
			(fill no)
			(layer "F.CrtYd")
		)
		(fp_rect
			(start -0.508 0.9398)
			(end 0.508 -0.9398)
			(stroke
				(width 0)
				(type default)
			)
			(fill no)
			(layer "F.Fab")
		)
		(pad "1" smd custom
			(at 0 -0.4445)
			(size 0.1397 0.1397)
			(layers "F.Cu" "F.Mask" "F.Paste")
			(net "PWM_BMC_A_ZONE_C")
			(options
				(clearance outline)
				(anchor circle)
			)
			(primitives
				(gr_poly
					(pts
						(arc
							(start -0.1778 -0.2794)
							(mid -0.249642 -0.249642)
							(end -0.2794 -0.1778)
						)
						(arc
							(start -0.2794 0.1778)
							(mid -0.249642 0.249642)
							(end -0.1778 0.2794)
						)
						(arc
							(start 0.1778 0.2794)
							(mid 0.249642 0.249642)
							(end 0.2794 0.1778)
						)
						(arc
							(start 0.2794 -0.1778)
							(mid 0.249642 -0.249642)
							(end 0.1778 -0.2794)
						)
					)
					(width 0)
					(fill yes)
				)
			)
		)
		(pad "2" smd custom
			(at 0 0.4445)
			(size 0.1397 0.1397)
			(layers "F.Cu" "F.Mask" "F.Paste")
			(net "GND")
			(options
				(clearance outline)
				(anchor circle)
			)
			(primitives
				(gr_poly
					(pts
						(arc
							(start -0.1778 -0.2794)
							(mid -0.249642 -0.249642)
							(end -0.2794 -0.1778)
						)
						(arc
							(start -0.2794 0.1778)
							(mid -0.249642 0.249642)
							(end -0.1778 0.2794)
						)
						(arc
							(start 0.1778 0.2794)
							(mid 0.249642 0.249642)
							(end 0.2794 0.1778)
						)
						(arc
							(start 0.2794 -0.1778)
							(mid 0.249642 -0.249642)
							(end 0.1778 -0.2794)
						)
					)
					(width 0)
					(fill yes)
				)
			)
		)
	)
)
